(kicad_pcb
	(version 20260206)
	(generator "pcbnew")
	(generator_version "10.0")
	(general
		(thickness 1.6)
		(legacy_teardrops no)
	)
	(paper "A4")
	(title_block
		(title "pdpb — Lightning_PDPB_BRD.brd")
		(comment 1 "Lightning (Wiwynn / Facebook NVMe JBOF) / footprints 230-237 of 1140")
	)
	(layers
		(0 "F.Cu" signal "TOP")
		(4 "In1.Cu" signal "L2GND")
		(6 "In2.Cu" signal "L3")
		(8 "In3.Cu" signal "L4VCC")
		(10 "In4.Cu" signal "L5VCC")
		(12 "In5.Cu" signal "L6")
		(14 "In6.Cu" signal "L7GND")
		(2 "B.Cu" signal "BOTTOM")
		(9 "F.Adhes" user "F.Adhesive")
		(11 "B.Adhes" user "B.Adhesive")
		(13 "F.Paste" user "Package Geometry/Pastemask Top")
		(15 "B.Paste" user "Package Geometry/Pastemask Bottom")
		(5 "F.SilkS" user "Ref Des/Silkscreen Top")
		(7 "B.SilkS" user "Ref Des/Silkscreen Bottom")
		(1 "F.Mask" user "Board Geometry/Soldermask Top")
		(3 "B.Mask" user "Board Geometry/Soldermask Bottom")
		(17 "Dwgs.User" user "User.Drawings")
		(19 "Cmts.User" user "User.Comments")
		(21 "Eco1.User" user "User.Eco1")
		(23 "Eco2.User" user "User.Eco2")
		(25 "Edge.Cuts" user "Board Geometry/Outline")
		(27 "Margin" user)
		(31 "F.CrtYd" user "Package Geometry/Place Bound Top")
		(29 "B.CrtYd" user "Package Geometry/Place Bound Bottom")
		(35 "F.Fab" user "Ref Des/Assembly Top")
		(33 "B.Fab" user "Ref Des/Assembly Bottom")
	)
	(footprint ""
		(layer "F.Cu")
		(at 43.020996 -351.872042 -90)
		(property "Reference" "R9939"
			(at 0 0 270)
			(layer "F.SilkS")
			(hide yes)
			(effects
				(font
					(size 1.27 1.27)
				)
			)
		)
		(property "Value" "4K7R2J-2-GP"
			(at 0.064008 -3.993896 270)
			(unlocked yes)
			(layer "F.Fab")
			(hide yes)
			(effects
				(font
					(size 1.016 1.016)
					(thickness 0.1524)
				)
			)
		)
		(property "Device Type" "R402H16"
			(at 0.064008 -5.517896 270)
			(unlocked yes)
			(layer "F.Fab")
			(hide yes)
			(effects
				(font
					(size 1.016 1.016)
					(thickness 0.1524)
				)
			)
		)
		(duplicate_pad_numbers_are_jumpers no)
		(fp_line
			(start -0.508 -0.9398)
			(end -0.508 0.9398)
			(stroke
				(width 0.1524)
				(type default)
			)
			(layer "F.SilkS")
		)
		(fp_line
			(start 0.508 -0.9398)
			(end -0.508 -0.9398)
			(stroke
				(width 0.1524)
				(type default)
			)
			(layer "F.SilkS")
		)
		(fp_rect
			(start -0.508 0.9398)
			(end 0.508 -0.9398)
			(stroke
				(width 0)
				(type default)
			)
			(fill no)
			(layer "F.CrtYd")
		)
		(fp_rect
			(start -0.508 0.9398)
			(end 0.508 -0.9398)
			(stroke
				(width 0)
				(type default)
			)
			(fill no)
			(layer "F.Fab")
		)
		(pad "1" smd custom
			(at 0 -0.4445 270)
			(size 0.1397 0.1397)
			(layers "F.Cu" "F.Mask" "F.Paste")
			(net "P3V3")
			(options
				(clearance outline)
				(anchor circle)
			)
			(primitives
				(gr_poly
					(pts
						(arc
							(start -0.1778 -0.2794)
							(mid -0.249642 -0.249642)
							(end -0.2794 -0.1778)
						)
						(arc
							(start -0.2794 0.1778)
							(mid -0.249642 0.249642)
							(end -0.1778 0.2794)
						)
						(arc
							(start 0.1778 0.2794)
							(mid 0.249642 0.249642)
							(end 0.2794 0.1778)
						)
						(arc
							(start 0.2794 -0.1778)
							(mid 0.249642 -0.249642)
							(end 0.1778 -0.2794)
						)
					)
					(width 0)
					(fill yes)
				)
			)
		)
		(pad "2" smd custom
			(at 0 0.4445 270)
			(size 0.1397 0.1397)
			(layers "F.Cu" "F.Mask" "F.Paste")
			(net "ATTN_LED_DR6_MOS_N")
			(options
				(clearance outline)
				(anchor circle)
			)
			(primitives
				(gr_poly
					(pts
						(arc
							(start -0.1778 -0.2794)
							(mid -0.249642 -0.249642)
							(end -0.2794 -0.1778)
						)
						(arc
							(start -0.2794 0.1778)
							(mid -0.249642 0.249642)
							(end -0.1778 0.2794)
						)
						(arc
							(start 0.1778 0.2794)
							(mid 0.249642 0.249642)
							(end 0.2794 0.1778)
						)
						(arc
							(start 0.2794 -0.1778)
							(mid 0.249642 -0.249642)
							(end 0.1778 -0.2794)
						)
					)
					(width 0)
					(fill yes)
				)
			)
		)
	)
	(footprint ""
		(layer "F.Cu")
		(at 36.2966 -198.2724 -90)
		(property "Reference" "R9832"
			(at 0 0 270)
			(layer "F.SilkS")
			(hide yes)
			(effects
				(font
					(size 1.27 1.27)
				)
			)
		)
		(property "Value" "2K2R5F-GP"
			(at 0 -8.9535 270)
			(unlocked yes)
			(layer "F.Fab")
			(hide yes)
			(effects
				(font
					(size 1.27 1.016)
					(thickness 0.1524)
				)
			)
		)
		(property "Device Type" "R805H24"
			(at 0 -10.6299 270)
			(unlocked yes)
			(layer "F.Fab")
			(hide yes)
			(effects
				(font
					(size 1.27 1.016)
					(thickness 0.1524)
				)
			)
		)
		(duplicate_pad_numbers_are_jumpers no)
		(fp_line
			(start -0.889 1.7018)
			(end 0.889 1.7018)
			(stroke
				(width 0.1524)
				(type default)
			)
			(layer "F.SilkS")
		)
		(fp_line
			(start 0.889 1.7018)
			(end 0.889 -0.508)
			(stroke
				(width 0.1524)
				(type default)
			)
			(layer "F.SilkS")
		)
		(fp_line
			(start -0.889 0.0762)
			(end -0.889 1.7018)
			(stroke
				(width 0.1524)
				(type default)
			)
			(layer "F.SilkS")
		)
		(fp_line
			(start -0.889 -1.7018)
			(end -0.889 0.2794)
			(stroke
				(width 0.1524)
				(type default)
			)
			(layer "F.SilkS")
		)
		(fp_line
			(start 0.889 -1.7018)
			(end 0.889 -0.381)
			(stroke
				(width 0.1524)
				(type default)
			)
			(layer "F.SilkS")
		)
		(fp_line
			(start 0.889 -1.7018)
			(end -0.889 -1.7018)
			(stroke
				(width 0.1524)
				(type default)
			)
			(layer "F.SilkS")
		)
		(fp_poly
			(pts
				(xy 0.9652 -1.778) (xy 0.9652 1.778) (xy -0.9652 1.778) (xy -0.9652 -1.778)
			)
			(stroke
				(width 0)
				(type default)
			)
			(fill no)
			(layer "F.CrtYd")
		)
		(fp_rect
			(start -0.9652 1.778)
			(end 0.9652 -1.778)
			(stroke
				(width 0)
				(type default)
			)
			(fill no)
			(layer "F.Fab")
		)
		(pad "1" smd rect
			(at 0 -0.9652 270)
			(size 1.397 1.143)
			(layers "F.Cu" "F.Mask" "F.Paste")
			(net "P12V_SSD8")
		)
		(pad "2" smd rect
			(at 0 0.9652 270)
			(size 1.397 1.143)
			(layers "F.Cu" "F.Mask" "F.Paste")
			(net "P12V_MOST8_GATE_D")
		)
	)
	(footprint ""
		(layer "F.Cu")
		(at 49.276 -41.275 -90)
		(property "Reference" "R9394"
			(at 0 0 270)
			(layer "F.SilkS")
			(hide yes)
			(effects
				(font
					(size 1.27 1.27)
				)
			)
		)
		(property "Value" "100R2J-2-GP"
			(at 0.064008 -3.993896 270)
			(unlocked yes)
			(layer "F.Fab")
			(hide yes)
			(effects
				(font
					(size 1.016 1.016)
					(thickness 0.1524)
				)
			)
		)
		(property "Device Type" "R402H14"
			(at 0.064008 -5.517896 270)
			(unlocked yes)
			(layer "F.Fab")
			(hide yes)
			(effects
				(font
					(size 1.016 1.016)
					(thickness 0.1524)
				)
			)
		)
		(duplicate_pad_numbers_are_jumpers no)
		(fp_line
			(start -0.508 -0.9398)
			(end -0.508 0.9398)
			(stroke
				(width 0.1524)
				(type default)
			)
			(layer "F.SilkS")
		)
		(fp_line
			(start 0.508 -0.9398)
			(end -0.508 -0.9398)
			(stroke
				(width 0.1524)
				(type default)
			)
			(layer "F.SilkS")
		)
		(fp_rect
			(start -0.508 0.9398)
			(end 0.508 -0.9398)
			(stroke
				(width 0)
				(type default)
			)
			(fill no)
			(layer "F.CrtYd")
		)
		(fp_rect
			(start -0.508 0.9398)
			(end 0.508 -0.9398)
			(stroke
				(width 0)
				(type default)
			)
			(fill no)
			(layer "F.Fab")
		)
		(pad "1" smd custom
			(at 0 -0.4445 270)
			(size 0.1397 0.1397)
			(layers "F.Cu" "F.Mask" "F.Paste")
			(net "P3V3")
			(options
				(clearance outline)
				(anchor circle)
			)
			(primitives
				(gr_poly
					(pts
						(arc
							(start -0.1778 -0.2794)
							(mid -0.249642 -0.249642)
							(end -0.2794 -0.1778)
						)
						(arc
							(start -0.2794 0.1778)
							(mid -0.249642 0.249642)
							(end -0.1778 0.2794)
						)
						(arc
							(start 0.1778 0.2794)
							(mid 0.249642 0.249642)
							(end 0.2794 0.1778)
						)
						(arc
							(start 0.2794 -0.1778)
							(mid 0.249642 -0.249642)
							(end 0.1778 -0.2794)
						)
					)
					(width 0)
					(fill yes)
				)
			)
		)
		(pad "2" smd custom
			(at 0 0.4445 270)
			(size 0.1397 0.1397)
			(layers "F.Cu" "F.Mask" "F.Paste")
			(net "DRV_ACT_9")
			(options
				(clearance outline)
				(anchor circle)
			)
			(primitives
				(gr_poly
					(pts
						(arc
							(start -0.1778 -0.2794)
							(mid -0.249642 -0.249642)
							(end -0.2794 -0.1778)
						)
						(arc
							(start -0.2794 0.1778)
							(mid -0.249642 0.249642)
							(end -0.1778 0.2794)
						)
						(arc
							(start 0.1778 0.2794)
							(mid 0.249642 0.249642)
							(end 0.2794 0.1778)
						)
						(arc
							(start 0.2794 -0.1778)
							(mid 0.249642 -0.249642)
							(end 0.1778 -0.2794)
						)
					)
					(width 0)
					(fill yes)
				)
			)
		)
	)
	(footprint ""
		(layer "F.Cu")
		(at 19.6596 -309.5498 180)
		(property "Reference" "R9260"
			(at 0 0 180)
			(layer "F.SilkS")
			(hide yes)
			(effects
				(font
					(size 1.27 1.27)
				)
			)
		)
		(property "Value" "2R2010F-GP"
			(at 0.0762 -4.5466 180)
			(unlocked yes)
			(layer "F.Fab")
			(hide yes)
			(effects
				(font
					(size 1.016 1.016)
					(thickness 0.1524)
				)
			)
		)
		(property "Device Type" "R2010H26"
			(at 0.0762 -6.1468 180)
			(unlocked yes)
			(layer "F.Fab")
			(hide yes)
			(effects
				(font
					(size 1.016 1.016)
					(thickness 0.1524)
				)
			)
		)
		(duplicate_pad_numbers_are_jumpers no)
		(fp_line
			(start 3.302 1.651)
			(end 3.302 -1.651)
			(stroke
				(width 0.1524)
				(type default)
			)
			(layer "F.SilkS")
		)
		(fp_line
			(start 3.302 -1.651)
			(end -3.302 -1.651)
			(stroke
				(width 0.1524)
				(type default)
			)
			(layer "F.SilkS")
		)
		(fp_line
			(start -3.302 1.651)
			(end 3.302 1.651)
			(stroke
				(width 0.1524)
				(type default)
			)
			(layer "F.SilkS")
		)
		(fp_line
			(start -3.302 -1.651)
			(end -3.302 1.651)
			(stroke
				(width 0.1524)
				(type default)
			)
			(layer "F.SilkS")
		)
		(fp_rect
			(start -3.3782 1.7272)
			(end 3.3782 -1.7272)
			(stroke
				(width 0)
				(type default)
			)
			(fill no)
			(layer "F.CrtYd")
		)
		(fp_poly
			(pts
				(xy 3.3782 -1.7272) (xy -3.3782 -1.7272) (xy -3.3782 1.7272) (xy 3.3782 1.7272)
			)
			(stroke
				(width 0)
				(type default)
			)
			(fill no)
			(layer "F.Fab")
		)
		(pad "1" smd rect
			(at -2.3495 0 180)
			(size 1.143 2.794)
			(layers "F.Cu" "F.Mask" "F.Paste")
			(net "P12V_SSD11")
		)
		(pad "2" smd rect
			(at 2.3495 0 180)
			(size 1.143 2.794)
			(layers "F.Cu" "F.Mask" "F.Paste")
			(net "12V_PRECH_SSD11")
		)
	)
	(footprint ""
		(layer "F.Cu")
		(at 100.4824 -101.5746 180)
		(property "Reference" "C9432"
			(at 0 0 180)
			(layer "F.SilkS")
			(hide yes)
			(effects
				(font
					(size 1.27 1.27)
				)
			)
		)
		(property "Value" "SCD1U16V2KX-3GP"
			(at 1.1811 -2.7051 180)
			(unlocked yes)
			(layer "F.Fab")
			(hide yes)
			(effects
				(font
					(size 1.016 1.016)
					(thickness 0.1524)
				)
			)
		)
		(property "Device Type" "C402H22"
			(at 1.1811 -4.2291 180)
			(unlocked yes)
			(layer "F.Fab")
			(hide yes)
			(effects
				(font
					(size 1.016 1.016)
					(thickness 0.1524)
				)
			)
		)
		(duplicate_pad_numbers_are_jumpers no)
		(fp_rect
			(start -0.4318 0.9525)
			(end 0.4318 -0.9525)
			(stroke
				(width 0)
				(type default)
			)
			(fill no)
			(layer "F.CrtYd")
		)
		(fp_rect
			(start -0.4318 0.9525)
			(end 0.4318 -0.9525)
			(stroke
				(width 0)
				(type default)
			)
			(fill no)
			(layer "F.Fab")
		)
		(pad "1" smd custom
			(at 0 -0.4445 180)
			(size 0.1524 0.1524)
			(layers "F.Cu" "F.Mask" "F.Paste")
			(net "VDD_DIFF_4")
			(options
				(clearance outline)
				(anchor circle)
			)
			(primitives
				(gr_poly
					(pts
						(arc
							(start 0.3048 -0.2032)
							(mid 0.275042 -0.275042)
							(end 0.2032 -0.3048)
						)
						(arc
							(start -0.2032 -0.3048)
							(mid -0.275042 -0.275042)
							(end -0.3048 -0.2032)
						)
						(arc
							(start -0.3048 0.2032)
							(mid -0.275042 0.275042)
							(end -0.2032 0.3048)
						)
						(arc
							(start 0.2032 0.3048)
							(mid 0.275042 0.275042)
							(end 0.3048 0.2032)
						)
					)
					(width 0)
					(fill yes)
				)
			)
		)
		(pad "2" smd custom
			(at 0 0.4445 180)
			(size 0.1524 0.1524)
			(layers "F.Cu" "F.Mask" "F.Paste")
			(net "GND")
			(options
				(clearance outline)
				(anchor circle)
			)
			(primitives
				(gr_poly
					(pts
						(arc
							(start 0.3048 -0.2032)
							(mid 0.275042 -0.275042)
							(end 0.2032 -0.3048)
						)
						(arc
							(start -0.2032 -0.3048)
							(mid -0.275042 -0.275042)
							(end -0.3048 -0.2032)
						)
						(arc
							(start -0.3048 0.2032)
							(mid -0.275042 0.275042)
							(end -0.2032 0.3048)
						)
						(arc
							(start 0.2032 0.3048)
							(mid 0.275042 0.275042)
							(end 0.3048 0.2032)
						)
					)
					(width 0)
					(fill yes)
				)
			)
		)
	)
	(footprint ""
		(layer "F.Cu")
		(at 45.632116 -37.453062 -90)
		(property "Reference" "R9843"
			(at 0 0 270)
			(layer "F.SilkS")
			(hide yes)
			(effects
				(font
					(size 1.27 1.27)
				)
			)
		)
		(property "Value" "0R2J-2-GP"
			(at 0.064008 -3.993896 270)
			(unlocked yes)
			(layer "F.Fab")
			(hide yes)
			(effects
				(font
					(size 1.016 1.016)
					(thickness 0.1524)
				)
			)
		)
		(property "Device Type" "R402H16"
			(at 0.064008 -5.517896 270)
			(unlocked yes)
			(layer "F.Fab")
			(hide yes)
			(effects
				(font
					(size 1.016 1.016)
					(thickness 0.1524)
				)
			)
		)
		(duplicate_pad_numbers_are_jumpers no)
		(fp_line
			(start -0.508 -0.9398)
			(end -0.508 0.9398)
			(stroke
				(width 0.1524)
				(type default)
			)
			(layer "F.SilkS")
		)
		(fp_line
			(start 0.508 -0.9398)
			(end -0.508 -0.9398)
			(stroke
				(width 0.1524)
				(type default)
			)
			(layer "F.SilkS")
		)
		(fp_rect
			(start -0.508 0.9398)
			(end 0.508 -0.9398)
			(stroke
				(width 0)
				(type default)
			)
			(fill no)
			(layer "F.CrtYd")
		)
		(fp_rect
			(start -0.508 0.9398)
			(end 0.508 -0.9398)
			(stroke
				(width 0)
				(type default)
			)
			(fill no)
			(layer "F.Fab")
		)
		(pad "1" smd custom
			(at 0 -0.4445 270)
			(size 0.1397 0.1397)
			(layers "F.Cu" "F.Mask" "F.Paste")
			(net "SSD_ACT_DR9_R")
			(options
				(clearance outline)
				(anchor circle)
			)
			(primitives
				(gr_poly
					(pts
						(arc
							(start -0.1778 -0.2794)
							(mid -0.249642 -0.249642)
							(end -0.2794 -0.1778)
						)
						(arc
							(start -0.2794 0.1778)
							(mid -0.249642 0.249642)
							(end -0.1778 0.2794)
						)
						(arc
							(start 0.1778 0.2794)
							(mid 0.249642 0.249642)
							(end 0.2794 0.1778)
						)
						(arc
							(start 0.2794 -0.1778)
							(mid 0.249642 -0.249642)
							(end 0.1778 -0.2794)
						)
					)
					(width 0)
					(fill yes)
				)
			)
		)
		(pad "2" smd custom
			(at 0 0.4445 270)
			(size 0.1397 0.1397)
			(layers "F.Cu" "F.Mask" "F.Paste")
			(net "SSD_ACT_DR9")
			(options
				(clearance outline)
				(anchor circle)
			)
			(primitives
				(gr_poly
					(pts
						(arc
							(start -0.1778 -0.2794)
							(mid -0.249642 -0.249642)
							(end -0.2794 -0.1778)
						)
						(arc
							(start -0.2794 0.1778)
							(mid -0.249642 0.249642)
							(end -0.1778 0.2794)
						)
						(arc
							(start 0.1778 0.2794)
							(mid 0.249642 0.249642)
							(end 0.2794 0.1778)
						)
						(arc
							(start 0.2794 -0.1778)
							(mid 0.249642 -0.249642)
							(end 0.1778 -0.2794)
						)
					)
					(width 0)
					(fill yes)
				)
			)
		)
	)
	(footprint ""
		(layer "F.Cu")
		(at 48.768 -34.29 90)
		(property "Reference" "R9841"
			(at 0 0 90)
			(layer "F.SilkS")
			(hide yes)
			(effects
				(font
					(size 1.27 1.27)
				)
			)
		)
		(property "Value" "0R2J-2-GP"
			(at 0.064008 -3.993896 90)
			(unlocked yes)
			(layer "F.Fab")
			(hide yes)
			(effects
				(font
					(size 1.016 1.016)
					(thickness 0.1524)
				)
			)
		)
		(property "Device Type" "R402H16"
			(at 0.064008 -5.517896 90)
			(unlocked yes)
			(layer "F.Fab")
			(hide yes)
			(effects
				(font
					(size 1.016 1.016)
					(thickness 0.1524)
				)
			)
		)
		(duplicate_pad_numbers_are_jumpers no)
		(fp_line
			(start 0.508 -0.9398)
			(end -0.508 -0.9398)
			(stroke
				(width 0.1524)
				(type default)
			)
			(layer "F.SilkS")
		)
		(fp_line
			(start -0.508 -0.9398)
			(end -0.508 0.9398)
			(stroke
				(width 0.1524)
				(type default)
			)
			(layer "F.SilkS")
		)
		(fp_rect
			(start -0.508 0.9398)
			(end 0.508 -0.9398)
			(stroke
				(width 0)
				(type default)
			)
			(fill no)
			(layer "F.CrtYd")
		)
		(fp_rect
			(start -0.508 0.9398)
			(end 0.508 -0.9398)
			(stroke
				(width 0)
				(type default)
			)
			(fill no)
			(layer "F.Fab")
		)
		(pad "1" smd custom
			(at 0 -0.4445 90)
			(size 0.1397 0.1397)
			(layers "F.Cu" "F.Mask" "F.Paste")
			(net "ATTN_LED_DR9_AND")
			(options
				(clearance outline)
				(anchor circle)
			)
			(primitives
				(gr_poly
					(pts
						(arc
							(start -0.1778 -0.2794)
							(mid -0.249642 -0.249642)
							(end -0.2794 -0.1778)
						)
						(arc
							(start -0.2794 0.1778)
							(mid -0.249642 0.249642)
							(end -0.1778 0.2794)
						)
						(arc
							(start 0.1778 0.2794)
							(mid 0.249642 0.249642)
							(end 0.2794 0.1778)
						)
						(arc
							(start 0.2794 -0.1778)
							(mid 0.249642 -0.249642)
							(end 0.1778 -0.2794)
						)
					)
					(width 0)
					(fill yes)
				)
			)
		)
		(pad "2" smd custom
			(at 0 0.4445 90)
			(size 0.1397 0.1397)
			(layers "F.Cu" "F.Mask" "F.Paste")
			(net "ATTN_LED_DR9_AND_R")
			(options
				(clearance outline)
				(anchor circle)
			)
			(primitives
				(gr_poly
					(pts
						(arc
							(start -0.1778 -0.2794)
							(mid -0.249642 -0.249642)
							(end -0.2794 -0.1778)
						)
						(arc
							(start -0.2794 0.1778)
							(mid -0.249642 0.249642)
							(end -0.1778 0.2794)
						)
						(arc
							(start 0.1778 0.2794)
							(mid 0.249642 0.249642)
							(end 0.2794 0.1778)
						)
						(arc
							(start 0.2794 -0.1778)
							(mid 0.249642 -0.249642)
							(end 0.1778 -0.2794)
						)
					)
					(width 0)
					(fill yes)
				)
			)
		)
	)
	(footprint ""
		(layer "F.Cu")
		(at 229.93096 -35.118802)
		(property "Reference" "C9522"
			(at 0 0 0)
			(layer "F.SilkS")
			(hide yes)
			(effects
				(font
					(size 1.27 1.27)
				)
			)
		)
		(property "Value" "SCD1U16V2KX-3GP"
			(at 1.1811 -2.7051 0)
			(unlocked yes)
			(layer "F.Fab")
			(hide yes)
			(effects
				(font
					(size 1.016 1.016)
					(thickness 0.1524)
				)
			)
		)
		(property "Device Type" "C402H22"
			(at 1.1811 -4.2291 0)
			(unlocked yes)
			(layer "F.Fab")
			(hide yes)
			(effects
				(font
					(size 1.016 1.016)
					(thickness 0.1524)
				)
			)
		)
		(duplicate_pad_numbers_are_jumpers no)
		(fp_rect
			(start -0.4318 0.9525)
			(end 0.4318 -0.9525)
			(stroke
				(width 0)
				(type default)
			)
			(fill no)
			(layer "F.CrtYd")
		)
		(fp_rect
			(start -0.4318 0.9525)
			(end 0.4318 -0.9525)
			(stroke
				(width 0)
				(type default)
			)
			(fill no)
			(layer "F.Fab")
		)
		(pad "1" smd custom
			(at 0 -0.4445)
			(size 0.1524 0.1524)
			(layers "F.Cu" "F.Mask" "F.Paste")
			(net "P3V3")
			(options
				(clearance outline)
				(anchor circle)
			)
			(primitives
				(gr_poly
					(pts
						(arc
							(start 0.3048 -0.2032)
							(mid 0.275042 -0.275042)
							(end 0.2032 -0.3048)
						)
						(arc
							(start -0.2032 -0.3048)
							(mid -0.275042 -0.275042)
							(end -0.3048 -0.2032)
						)
						(arc
							(start -0.3048 0.2032)
							(mid -0.275042 0.275042)
							(end -0.2032 0.3048)
						)
						(arc
							(start 0.2032 0.3048)
							(mid 0.275042 0.275042)
							(end 0.3048 0.2032)
						)
					)
					(width 0)
					(fill yes)
				)
			)
		)
		(pad "2" smd custom
			(at 0 0.4445)
			(size 0.1524 0.1524)
			(layers "F.Cu" "F.Mask" "F.Paste")
			(net "GND")
			(options
				(clearance outline)
				(anchor circle)
			)
			(primitives
				(gr_poly
					(pts
						(arc
							(start 0.3048 -0.2032)
							(mid 0.275042 -0.275042)
							(end 0.2032 -0.3048)
						)
						(arc
							(start -0.2032 -0.3048)
							(mid -0.275042 -0.275042)
							(end -0.3048 -0.2032)
						)
						(arc
							(start -0.3048 0.2032)
							(mid -0.275042 0.275042)
							(end -0.2032 0.3048)
						)
						(arc
							(start 0.2032 0.3048)
							(mid 0.275042 0.275042)
							(end 0.3048 0.2032)
						)
					)
					(width 0)
					(fill yes)
				)
			)
		)
	)
)
